# S9S_MB_2U (Grand Teton) — schematic netlist excerpt (pin names and nets, part order shuffled) for the footprints in the layout excerpt that follows; sources: Cadence DE-HDL packaged netlist, KiCad conversion of 03242023_DA0F0TMBIJ0_F0T_Motherboard_J_brd_V01_OCP.brd

R3657  Q_RES  10K 1% EMPTY  pkg 0402LF  page 152 : A = P3V3_AUX ; B = USB_HUB_OVCUR2
R4461  Q_RES  0 5% CHIP  pkg 0402LF  page 196 : A = USB2_HOST_PCH_0_DN ; B = USB2_HUB_2_BUF_EXT_R_DN

(kicad_pcb
	(version 20260206)
	(generator "pcbnew")
	(generator_version "10.0")
	(general
		(thickness 1.6)
		(legacy_teardrops no)
	)
	(paper "A4")
	(title_block
		(title "03242023_DA0F0TMBIJ0_F0T_Motherboard_J_brd_V01_OCP.brd")
		(comment 1 "Grand Teton / footprints 2116-2117 of 6105")
	)
	(layers
		(0 "F.Cu" signal "TOP")
		(4 "In1.Cu" signal "GND")
		(6 "In2.Cu" signal "IN1")
		(8 "In3.Cu" signal "GND1")
		(10 "In4.Cu" signal "IN2")
		(12 "In5.Cu" signal "GND2")
		(14 "In6.Cu" signal "IN3")
		(16 "In7.Cu" signal "GND3")
		(18 "In8.Cu" signal "VCC")
		(20 "In9.Cu" signal "VCC1")
		(22 "In10.Cu" signal "GND4")
		(24 "In11.Cu" signal "IN4")
		(26 "In12.Cu" signal "GND5")
		(28 "In13.Cu" signal "IN5")
		(30 "In14.Cu" signal "GND6")
		(32 "In15.Cu" signal "IN6")
		(34 "In16.Cu" signal "GND7")
		(2 "B.Cu" signal "BOTTOM")
		(9 "F.Adhes" user "F.Adhesive")
		(11 "B.Adhes" user "B.Adhesive")
		(13 "F.Paste" user "Package Geometry/Pastemask Top")
		(15 "B.Paste" user "Package Geometry/Pastemask Bottom")
		(5 "F.SilkS" user "Ref Des/Silkscreen Top")
		(7 "B.SilkS" user "Ref Des/Silkscreen Bottom")
		(1 "F.Mask" user "Board Geometry/Soldermask Top")
		(3 "B.Mask" user "Board Geometry/Soldermask Bottom")
		(17 "Dwgs.User" user "User.Drawings")
		(19 "Cmts.User" user "User.Comments")
		(21 "Eco1.User" user "User.Eco1")
		(23 "Eco2.User" user "User.Eco2")
		(25 "Edge.Cuts" user "Board Geometry/Outline")
		(27 "Margin" user)
		(31 "F.CrtYd" user "Package Geometry/Place Bound Top")
		(29 "B.CrtYd" user "Package Geometry/Place Bound Bottom")
		(35 "F.Fab" user "Ref Des/Assembly Top")
		(33 "B.Fab" user "Ref Des/Assembly Bottom")
	)
	(footprint ""
		(layer "F.Cu")
		(at 21.176996 -99.413314 180)
		(property "Reference" "R3657"
			(at 0 0 180)
			(layer "F.SilkS")
			(hide yes)
			(effects
				(font
					(size 1.27 1.27)
				)
			)
		)
		(property "Value" ""
			(at 0 0 180)
			(layer "F.Fab")
			(effects
				(font
					(size 1.27 1.27)
				)
			)
		)
		(duplicate_pad_numbers_are_jumpers no)
		(fp_line
			(start 0.7874 0.4064)
			(end -0.7874 0.4064)
			(stroke
				(width 0.1524)
				(type default)
			)
			(layer "F.SilkS")
		)
		(fp_line
			(start 0.7874 -0.4064)
			(end 0.7874 0.4064)
			(stroke
				(width 0.1524)
				(type default)
			)
			(layer "F.SilkS")
		)
		(fp_line
			(start -0.7874 0.4064)
			(end -0.7874 -0.4064)
			(stroke
				(width 0.1524)
				(type default)
			)
			(layer "F.SilkS")
		)
		(fp_line
			(start -0.7874 -0.4064)
			(end 0.7874 -0.4064)
			(stroke
				(width 0.1524)
				(type default)
			)
			(layer "F.SilkS")
		)
		(fp_line
			(start 0.67945 0.3048)
			(end 0.120396 0.3048)
			(stroke
				(width 0.1)
				(type default)
			)
			(layer "F.Fab")
		)
		(fp_line
			(start 0.67945 -0.3048)
			(end 0.67945 0.3048)
			(stroke
				(width 0.1)
				(type default)
			)
			(layer "F.Fab")
		)
		(fp_line
			(start 0.12065 -0.2794)
			(end 0.12065 -0.3048)
			(stroke
				(width 0.1)
				(type default)
			)
			(layer "F.Fab")
		)
		(fp_line
			(start 0.12065 -0.3048)
			(end 0.67945 -0.3048)
			(stroke
				(width 0.1)
				(type default)
			)
			(layer "F.Fab")
		)
		(fp_line
			(start 0.120396 0.3048)
			(end 0.120396 0.2794)
			(stroke
				(width 0.1)
				(type default)
			)
			(layer "F.Fab")
		)
		(fp_line
			(start 0.120396 0.2794)
			(end -0.12065 0.2794)
			(stroke
				(width 0.1)
				(type default)
			)
			(layer "F.Fab")
		)
		(fp_line
			(start -0.12065 0.3048)
			(end -0.67945 0.3048)
			(stroke
				(width 0.1)
				(type default)
			)
			(layer "F.Fab")
		)
		(fp_line
			(start -0.12065 0.2794)
			(end -0.12065 0.3048)
			(stroke
				(width 0.1)
				(type default)
			)
			(layer "F.Fab")
		)
		(fp_line
			(start -0.12065 -0.2794)
			(end 0.12065 -0.2794)
			(stroke
				(width 0.1)
				(type default)
			)
			(layer "F.Fab")
		)
		(fp_line
			(start -0.12065 -0.305054)
			(end -0.12065 -0.2794)
			(stroke
				(width 0.1)
				(type default)
			)
			(layer "F.Fab")
		)
		(fp_line
			(start -0.67945 0.3048)
			(end -0.67945 -0.305054)
			(stroke
				(width 0.1)
				(type default)
			)
			(layer "F.Fab")
		)
		(fp_line
			(start -0.67945 -0.305054)
			(end -0.12065 -0.305054)
			(stroke
				(width 0.1)
				(type default)
			)
			(layer "F.Fab")
		)
		(pad "1" smd circle
			(at -0.40005 0 180)
			(size 0 0)
			(layers "F.Cu" "F.Mask" "F.Paste")
			(net "P3V3_AUX")
		)
		(pad "2" smd circle
			(at 0.40005 0 180)
			(size 0 0)
			(layers "F.Cu" "F.Mask" "F.Paste")
			(net "USB_HUB_OVCUR2")
		)
	)
	(footprint ""
		(layer "F.Cu")
		(at 157.061408 -45.462698 -90)
		(property "Reference" "R4461"
			(at 0 0 270)
			(layer "F.SilkS")
			(hide yes)
			(effects
				(font
					(size 1.27 1.27)
				)
			)
		)
		(property "Value" ""
			(at 0 0 270)
			(layer "F.Fab")
			(effects
				(font
					(size 1.27 1.27)
				)
			)
		)
		(duplicate_pad_numbers_are_jumpers no)
		(fp_line
			(start -0.7874 -0.4064)
			(end 0.7874 -0.4064)
			(stroke
				(width 0.1524)
				(type default)
			)
			(layer "F.SilkS")
		)
		(fp_line
			(start 0.7874 -0.4064)
			(end 0.7874 0.4064)
			(stroke
				(width 0.1524)
				(type default)
			)
			(layer "F.SilkS")
		)
		(fp_line
			(start -0.67945 0.3048)
			(end -0.67945 -0.305054)
			(stroke
				(width 0.1)
				(type default)
			)
			(layer "F.Fab")
		)
		(fp_line
			(start -0.12065 0.3048)
			(end -0.67945 0.3048)
			(stroke
				(width 0.1)
				(type default)
			)
			(layer "F.Fab")
		)
		(fp_line
			(start 0.120396 0.3048)
			(end 0.120396 0.2794)
			(stroke
				(width 0.1)
				(type default)
			)
			(layer "F.Fab")
		)
		(fp_line
			(start 0.67945 0.3048)
			(end 0.120396 0.3048)
			(stroke
				(width 0.1)
				(type default)
			)
			(layer "F.Fab")
		)
		(fp_line
			(start -0.12065 0.2794)
			(end -0.12065 0.3048)
			(stroke
				(width 0.1)
				(type default)
			)
			(layer "F.Fab")
		)
		(fp_line
			(start 0.120396 0.2794)
			(end -0.12065 0.2794)
			(stroke
				(width 0.1)
				(type default)
			)
			(layer "F.Fab")
		)
		(fp_line
			(start -0.12065 -0.2794)
			(end 0.12065 -0.2794)
			(stroke
				(width 0.1)
				(type default)
			)
			(layer "F.Fab")
		)
		(fp_line
			(start 0.12065 -0.2794)
			(end 0.12065 -0.3048)
			(stroke
				(width 0.1)
				(type default)
			)
			(layer "F.Fab")
		)
		(fp_line
			(start 0.12065 -0.3048)
			(end 0.67945 -0.3048)
			(stroke
				(width 0.1)
				(type default)
			)
			(layer "F.Fab")
		)
		(fp_line
			(start 0.67945 -0.3048)
			(end 0.67945 0.3048)
			(stroke
				(width 0.1)
				(type default)
			)
			(layer "F.Fab")
		)
		(fp_line
			(start -0.67945 -0.305054)
			(end -0.12065 -0.305054)
			(stroke
				(width 0.1)
				(type default)
			)
			(layer "F.Fab")
		)
		(fp_line
			(start -0.12065 -0.305054)
			(end -0.12065 -0.2794)
			(stroke
				(width 0.1)
				(type default)
			)
			(layer "F.Fab")
		)
		(pad "1" smd rect
			(at -0.40005 0 90)
			(size 0.4572 0.508)
			(layers "F.Cu" "F.Mask" "F.Paste")
			(net "USB2_HOST_PCH_0_DN")
		)
		(pad "2" smd rect
			(at 0.40005 0 90)
			(size 0.4572 0.508)
			(layers "F.Cu" "F.Mask" "F.Paste")
			(net "USB2_HUB_2_BUF_EXT_R_DN")
		)
	)
)
